FILE_TYPE = MULTI_PHYS_TABLE;
PART 'CAP_A'
{========================================================================================}
:VALUE      | VOLTAGE | TOLERANCE | PACK_TYPE | MATERIAL | PART_NUMBER      = ENVCOMP                  | PART_NUMBER   | JEDEC_TYPE  | ALT_SYMBOLS                      | VALUE      | RATED_VOLTAGE | TOL      | CLASS      | DESCRIPTION                                    | HEIGHT     | COMPONENT_TYPE | LEAD_LENGTH | LPID   | SPEED_URL                                                                                                                        | STATUS        | RPL   | AML   | BUS_UNIT          | DAYS  ;
{========================================================================================}
'10.0pF'   | '50V'   | '5%'      | '0402V'    | 'COG'    | 'A36094-025'(!) = 'YES;YES;YES;UNK;ok;VLD' | 'A36094-025'  | 'SMC0402A'  | '(SMX0402V,SMX0402AV,SMX0402BV)' | '10.0pF'   | '50V'         | '5%'     | 'DISCRETE' | 'CHIP0402'                                     | '0.024 IN' | 'CHIP0402'     | ''          | '1142' | 'http://speed.intel.com:8081/speed/module/pdm/item/pdm_item_detail_direct.asp?item_cde=A36094-025&item_rev=01&url_param=unused'  | 'Approved'    | 'YES' | '12'  | 'SMO_BOARDS'      | '56' 
'10.0pF'   | '50V'   | '5%'      | '0402V'    | 'EMPTY'  | 'A36094-025'(!) = 'YES;YES;YES;UNK;ok;VLD' | 'A36094-025'  | 'SMC0402A'  | '(SMX0402V,SMX0402AV,SMX0402BV)' | 'NA'       | '50V'         | '5%'     | 'DISCRETE' | 'CHIP0402'                                     | '0.024 IN' | 'CHIP0402'     | ''          | '1142' | 'http://speed.intel.com:8081/speed/module/pdm/item/pdm_item_detail_direct.asp?item_cde=A36094-025&item_rev=01&url_param=unused'  | 'Approved'    | 'YES' | '12'  | 'SMO_BOARDS'      | '56' 
'47.0pF'   | '50V'   | '5%'      | '0402V'    | 'COG'    | 'A36095-025'(!) = 'YES;YES;YES;UNK;ok;VLD' | 'A36095-025'  | 'SMC0402A'  | '(SMX0402V,SMX0402AV,SMX0402BV)' | '47.0pF'   | '50V'         | '5%'     | 'DISCRETE' | 'CHIP0402'                                     | '0.034 IN' | 'CHIP0402'     | ''          | '1142' | 'http://speed.intel.com:8081/speed/module/pdm/item/pdm_item_detail_direct.asp?item_cde=A36095-025&item_rev=01&url_param=unused'  | 'Approved'    | 'YES' | '10'  | 'SMO_BOARDS'      | '56' 
'47.0pF'   | '50V'   | '5%'      | '0402V'    | 'EMPTY'  | 'A36095-025'(!) = 'YES;YES;YES;UNK;ok;VLD' | 'A36095-025'  | 'SMC0402A'  | '(SMX0402V,SMX0402AV,SMX0402BV)' | 'NA'       | '50V'         | '5%'     | 'DISCRETE' | 'CHIP0402'                                     | '0.034 IN' | 'CHIP0402'     | ''          | '1142' | 'http://speed.intel.com:8081/speed/module/pdm/item/pdm_item_detail_direct.asp?item_cde=A36095-025&item_rev=01&url_param=unused'  | 'Approved'    | 'YES' | '10'  | 'SMO_BOARDS'      | '56' 
'100.0pF'  | '50V'   | '5%'      | '0402V'    | 'COG'    | 'A36095-026'(!) = 'YES;YES;YES;UNK;ok;VLD' | 'A36095-026'  | 'SMC0402A'  | '(SMX0402V,SMX0402AV,SMX0402BV)' | '100.0pF'  | '50V'         | '5%'     | 'DISCRETE' | 'CHIP0402'                                     | '0.024 IN' | 'CHIP0402'     | ''          | '1142' | 'http://speed.intel.com:8081/speed/module/pdm/item/pdm_item_detail_direct.asp?item_cde=A36095-026&item_rev=01&url_param=unused'  | 'Approved'    | 'NO'  | '12'  | 'SMO_BOARDS'      | '56' 
'100.0pF'  | '50V'   | '5%'      | '0402V'    | 'EMPTY'  | 'A36095-026'(!) = 'YES;YES;YES;UNK;ok;VLD' | 'A36095-026'  | 'SMC0402A'  | '(SMX0402V,SMX0402AV,SMX0402BV)' | 'NA'       | '50V'         | '5%'     | 'DISCRETE' | 'CHIP0402'                                     | '0.024 IN' | 'CHIP0402'     | ''          | '1142' | 'http://speed.intel.com:8081/speed/module/pdm/item/pdm_item_detail_direct.asp?item_cde=A36095-026&item_rev=01&url_param=unused'  | 'Approved'    | 'NO'  | '12'  | 'SMO_BOARDS'      | '56' 
'22.0pF'   | '50V'   | '5%'      | '0402V'    | 'COG'    | 'A36095-030'(!) = 'YES;YES;YES;UNK;ok;CIP' | 'A36095-030'  | 'SMC0402A'  | '(SMX0402V,SMX0402AV,SMX0402BV)' | '22.0pF'   | '50V'         | '5%'     | 'DISCRETE' | 'CHIP0402'                                     | '0.024 IN' | 'CHIP0402'     | ''          | '1142' | 'http://speed.intel.com:8081/speed/module/pdm/item/pdm_item_detail_direct.asp?item_cde=A36095-030&item_rev=01&url_param=unused'  | 'Approved'    | 'YES' | '12'  | 'SMO_BOARDS'      | '56' 
'22.0pF'   | '50V'   | '5%'      | '0402V'    | 'EMPTY'  | 'A36095-030'(!) = 'YES;YES;YES;UNK;ok;CIP' | 'A36095-030'  | 'SMC0402A'  | '(SMX0402V,SMX0402AV,SMX0402BV)' | 'NA'       | '50V'         | '5%'     | 'DISCRETE' | 'CHIP0402'                                     | '0.024 IN' | 'CHIP0402'     | ''          | '1142' | 'http://speed.intel.com:8081/speed/module/pdm/item/pdm_item_detail_direct.asp?item_cde=A36095-030&item_rev=01&url_param=unused'  | 'Approved'    | 'YES' | '12'  | 'SMO_BOARDS'      | '56' 
'33.0pF'   | '50V'   | '5%'      | '0402V'    | 'COG'    | 'A36095-031'(!) = 'YES;YES;YES;UNK;ok;CIP' | 'A36095-031'  | 'SMC0402A'  | '(SMX0402V,SMX0402AV,SMX0402BV)' | '33.0pF'   | '50V'         | '5%'     | 'DISCRETE' | 'CHIP0402'                                     | '0.024 IN' | 'CHIP0402'     | ''          | '1142' | 'http://speed.intel.com:8081/speed/module/pdm/item/pdm_item_detail_direct.asp?item_cde=A36095-031&item_rev=01&url_param=unused'  | 'Approved'    | 'YES' | '11'  | 'SMO_BOARDS'      | '56' 
'33.0pF'   | '50V'   | '5%'      | '0402V'    | 'EMPTY'  | 'A36095-031'(!) = 'YES;YES;YES;UNK;ok;CIP' | 'A36095-031'  | 'SMC0402A'  | '(SMX0402V,SMX0402AV,SMX0402BV)' | 'NA'       | '50V'         | '5%'     | 'DISCRETE' | 'CHIP0402'                                     | '0.024 IN' | 'CHIP0402'     | ''          | '1142' | 'http://speed.intel.com:8081/speed/module/pdm/item/pdm_item_detail_direct.asp?item_cde=A36095-031&item_rev=01&url_param=unused'  | 'Approved'    | 'YES' | '11'  | 'SMO_BOARDS'      | '56' 
'27.0pF'   | '50V'   | '5%'      | '0402V'    | 'COG'    | 'A36095-038'(!) = 'YES;YES;YES;UNK;ok;CIP' | 'A36095-038'  | 'SMC0402A'  | '(SMX0402V,SMX0402AV,SMX0402BV)' | '27.0pF'   | '50V'         | '5%'     | 'DISCRETE' | 'CHIP0402'                                     | '0.022 IN' | 'CHIP0402'     | ''          | '1142' | 'http://speed.intel.com:8081/speed/module/pdm/item/pdm_item_detail_direct.asp?item_cde=A36095-038&item_rev=01&url_param=unused'  | 'Approved'    | 'YES' | '9'   | 'SMO_BOARDS'      | '56' 
'27.0pF'   | '50V'   | '5%'      | '0402V'    | 'EMPTY'  | 'A36095-038'(!) = 'YES;YES;YES;UNK;ok;CIP' | 'A36095-038'  | 'SMC0402A'  | '(SMX0402V,SMX0402AV,SMX0402BV)' | 'NA'       | '50V'         | '5%'     | 'DISCRETE' | 'CHIP0402'                                     | '0.022 IN' | 'CHIP0402'     | ''          | '1142' | 'http://speed.intel.com:8081/speed/module/pdm/item/pdm_item_detail_direct.asp?item_cde=A36095-038&item_rev=01&url_param=unused'  | 'Approved'    | 'YES' | '9'   | 'SMO_BOARDS'      | '56' 
'18pF'     | '50V'   | '5%'      | '0402V'    | 'C0G'    | 'A36095-042'(!) = 'YES;YES;YES;UNK;ok;VLD' | 'A36095-042'  | 'SMC0402A'  | '(SMX0402V,SMX0402AV,SMX0402BV)' | '18PF'     | '50V'         | '5%'     | 'DISCRETE' | 'CHIP0402'                                     | '0.022 IN' | 'CHIP0402'     | ''          | '1142' | 'http://speed.intel.com:8081/speed/module/pdm/item/pdm_item_detail_direct.asp?item_cde=A36095-042&item_rev=01&url_param=unused'  | 'Approved'    | 'YES' | '10'  | 'SMO_BOARDS'      | '56' 
'18pF'     | '50V'   | '5%'      | '0402V'    | 'EMPTY'  | 'A36095-042'(!) = 'YES;YES;YES;UNK;ok;VLD' | 'A36095-042'  | 'SMC0402A'  | '(SMX0402V,SMX0402AV,SMX0402BV)' | 'NA'       | '50V'         | '5%'     | 'DISCRETE' | 'CHIP0402'                                     | '0.022 IN' | 'CHIP0402'     | ''          | '1142' | 'http://speed.intel.com:8081/speed/module/pdm/item/pdm_item_detail_direct.asp?item_cde=A36095-042&item_rev=01&url_param=unused'  | 'Approved'    | 'YES' | '10'  | 'SMO_BOARDS'      | '56' 
'12.0pF'   | '50V'   | '5%'      | '0402V'    | 'COG'    | 'A36095-043'(!) = 'YES;YES;YES;UNK;ok;VLD' | 'A36095-043'  | 'SMC0402A'  | '(SMX0402V,SMX0402AV,SMX0402BV)' | '12.0pF'   | '50V'         | '5%'     | 'DISCRETE' | 'CHIP0402'                                     | '0.024 IN' | 'CHIP0402'     | ''          | '1142' | 'http://speed.intel.com:8081/speed/module/pdm/item/pdm_item_detail_direct.asp?item_cde=A36095-043&item_rev=01&url_param=unused'  | 'Approved'    | 'YES' | '8'   | 'SMO_BOARDS'      | '56' 
'12.0pF'   | '50V'   | '5%'      | '0402V'    | 'EMPTY'  | 'A36095-043'(!) = 'YES;YES;YES;UNK;ok;VLD' | 'A36095-043'  | 'SMC0402A'  | '(SMX0402V,SMX0402AV,SMX0402BV)' | 'NA'       | '50V'         | '5%'     | 'DISCRETE' | 'CHIP0402'                                     | '0.024 IN' | 'CHIP0402'     | ''          | '1142' | 'http://speed.intel.com:8081/speed/module/pdm/item/pdm_item_detail_direct.asp?item_cde=A36095-043&item_rev=01&url_param=unused'  | 'Approved'    | 'YES' | '8'   | 'SMO_BOARDS'      | '56' 
'15.0pF'   | '50V'   | '5%'      | '0402V'    | 'COG'    | 'A36095-047'(!) = 'YES;YES;YES;UNK;ok;VLD' | 'A36095-047'  | 'SMC0402A'  | '(SMX0402V,SMX0402AV,SMX0402BV)' | '15.0pF'   | '50V'         | '5%'     | 'DISCRETE' | 'CHIP0402'                                     | '0.024 IN' | 'CHIP0402'     | ''          | '1142' | 'http://speed.intel.com:8081/speed/module/pdm/item/pdm_item_detail_direct.asp?item_cde=A36095-047&item_rev=01&url_param=unused'  | 'Approved'    | 'YES' | '13'  | 'SMO_BOARDS'      | '56' 
'15.0pF'   | '50V'   | '5%'      | '0402V'    | 'EMPTY'  | 'A36095-047'(!) = 'YES;YES;YES;UNK;ok;VLD' | 'A36095-047'  | 'SMC0402A'  | '(SMX0402V,SMX0402AV,SMX0402BV)' | 'NA'       | '50V'         | '5%'     | 'DISCRETE' | 'CHIP0402'                                     | '0.024 IN' | 'CHIP0402'     | ''          | '1142' | 'http://speed.intel.com:8081/speed/module/pdm/item/pdm_item_detail_direct.asp?item_cde=A36095-047&item_rev=01&url_param=unused'  | 'Approved'    | 'YES' | '13'  | 'SMO_BOARDS'      | '56' 
'0.1uF'    | '16V'   | '10%'     | '0402V'    | 'EMPTY'  | 'A36096-030'(!) = 'YES;YES;YES;UNK;ok;VLD' | 'A36096-030'  | 'SMC0402A'  | '(SMX0402V,SMX0402AV,SMX0402BV)' | 'NA'       | '16V'         | '10%'    | 'DISCRETE' | 'CHIP0402'                                     | '0.024 IN' | 'CHIP0402'     | ''          | '1142' | 'http://speed.intel.com:8081/speed/module/pdm/item/pdm_item_detail_direct.asp?item_cde=A36096-030&item_rev=01&url_param=unused'  | 'Approved'    | 'YES' | '12'  | 'SMO_BOARDS'      | '56' 
'0.1uF'    | '16V'   | '10%'     | '0402V'    | 'X7R'    | 'A36096-030'(!) = 'YES;YES;YES;UNK;ok;VLD' | 'A36096-030'  | 'SMC0402A'  | '(SMX0402V,SMX0402AV,SMX0402BV)' | '0.1uF'    | '16V'         | '10%'    | 'DISCRETE' | 'CHIP0402'                                     | '0.024 IN' | 'CHIP0402'     | ''          | '1142' | 'http://speed.intel.com:8081/speed/module/pdm/item/pdm_item_detail_direct.asp?item_cde=A36096-030&item_rev=01&url_param=unused'  | 'Approved'    | 'YES' | '12'  | 'SMO_BOARDS'      | '56' 
'0.01uF'   | '25V'   | '10%'     | '0402V'    | 'EMPTY'  | 'A36096-045'(!) = 'YES;YES;YES;UNK;ok;CIP' | 'A36096-045'  | 'SMC0402A'  | '(SMX0402V,SMX0402AV,SMX0402BV)' | 'NA'       | '25V'         | '10%'    | 'DISCRETE' | 'CHIP0402'                                     | '0.024 IN' | 'CHIP0402'     | ''          | '1142' | 'http://speed.intel.com:8081/speed/module/pdm/item/pdm_item_detail_direct.asp?item_cde=A36096-045&item_rev=01&url_param=unused'  | 'Approved'    | 'YES' | '13'  | 'SMO_BOARDS'      | '56' 
'0.01uF'   | '25V'   | '10%'     | '0402V'    | 'X7R'    | 'A36096-045'(!) = 'YES;YES;YES;UNK;ok;CIP' | 'A36096-045'  | 'SMC0402A'  | '(SMX0402V,SMX0402AV,SMX0402BV)' | '0.01uF'   | '25V'         | '10%'    | 'DISCRETE' | 'CHIP0402'                                     | '0.024 IN' | 'CHIP0402'     | ''          | '1142' | 'http://speed.intel.com:8081/speed/module/pdm/item/pdm_item_detail_direct.asp?item_cde=A36096-045&item_rev=01&url_param=unused'  | 'Approved'    | 'YES' | '13'  | 'SMO_BOARDS'      | '56' 
'1000pF'   | '50V'   | '10%'     | '0402V'    | 'EMPTY'  | 'A36096-046'(!) = 'YES;YES;YES;UNK;ok;CIP' | 'A36096-046'  | 'SMC0402A'  | '(SMX0402V,SMX0402AV,SMX0402BV)' | 'NA'       | '50V'         | '10%'    | 'DISCRETE' | 'CHIP0402'                                     | '0.024 IN' | 'CHIP0402'     | ''          | '1142' | 'http://speed.intel.com:8081/speed/module/pdm/item/pdm_item_detail_direct.asp?item_cde=A36096-046&item_rev=01&url_param=unused'  | 'Approved'    | 'YES' | '14'  | 'SMO_BOARDS'      | '56' 
'1000pF'   | '50V'   | '10%'     | '0402V'    | 'X7R'    | 'A36096-046'(!) = 'YES;YES;YES;UNK;ok;CIP' | 'A36096-046'  | 'SMC0402A'  | '(SMX0402V,SMX0402AV,SMX0402BV)' | '1000pF'   | '50V'         | '10%'    | 'DISCRETE' | 'CHIP0402'                                     | '0.024 IN' | 'CHIP0402'     | ''          | '1142' | 'http://speed.intel.com:8081/speed/module/pdm/item/pdm_item_detail_direct.asp?item_cde=A36096-046&item_rev=01&url_param=unused'  | 'Approved'    | 'YES' | '14'  | 'SMO_BOARDS'      | '56' 
'470pF'    | '50V'   | '10%'     | '0402V'    | 'EMPTY'  | 'A36096-049'(!) = 'YES;YES;YES;UNK;ok;VLD' | 'A36096-049'  | 'SMC0402A'  | '(SMX0402V,SMX0402AV,SMX0402BV)' | 'NA'       | '50V'         | '10%'    | 'DISCRETE' | 'CHIP0402'                                     | '0.024 IN' | 'CHIP0402'     | ''          | '1142' | 'http://speed.intel.com:8081/speed/module/pdm/item/pdm_item_detail_direct.asp?item_cde=A36096-049&item_rev=01&url_param=unused'  | 'Approved'    | 'YES' | '13'  | 'SMO_BOARDS'      | '56' 
'470pF'    | '50V'   | '10%'     | '0402V'    | 'X7R'    | 'A36096-049'(!) = 'YES;YES;YES;UNK;ok;VLD' | 'A36096-049'  | 'SMC0402A'  | '(SMX0402V,SMX0402AV,SMX0402BV)' | '470pF'    | '50V'         | '10%'    | 'DISCRETE' | 'CHIP0402'                                     | '0.024 IN' | 'CHIP0402'     | ''          | '1142' | 'http://speed.intel.com:8081/speed/module/pdm/item/pdm_item_detail_direct.asp?item_cde=A36096-049&item_rev=01&url_param=unused'  | 'Approved'    | 'YES' | '13'  | 'SMO_BOARDS'      | '56' 
'220pF'    | '50V'   | '10%'     | '0402V'    | 'EMPTY'  | 'A36096-050'(!) = 'YES;YES;YES;UNK;ok;VLD' | 'A36096-050'  | 'SMC0402A'  | '(SMX0402V,SMX0402AV,SMX0402BV)' | 'NA'       | '50V'         | '10%'    | 'DISCRETE' | 'CHIP0402'                                     | '0.024 IN' | 'CHIP0402'     | ''          | '1142' | 'http://speed.intel.com:8081/speed/module/pdm/item/pdm_item_detail_direct.asp?item_cde=A36096-050&item_rev=01&url_param=unused'  | 'Approved'    | 'YES' | '12'  | 'SMO_BOARDS'      | '56' 
'220pF'    | '50V'   | '10%'     | '0402V'    | 'X7R'    | 'A36096-050'(!) = 'YES;YES;YES;UNK;ok;VLD' | 'A36096-050'  | 'SMC0402A'  | '(SMX0402V,SMX0402AV,SMX0402BV)' | '220pF'    | '50V'         | '10%'    | 'DISCRETE' | 'CHIP0402'                                     | '0.024 IN' | 'CHIP0402'     | ''          | '1142' | 'http://speed.intel.com:8081/speed/module/pdm/item/pdm_item_detail_direct.asp?item_cde=A36096-050&item_rev=01&url_param=unused'  | 'Approved'    | 'YES' | '12'  | 'SMO_BOARDS'      | '56' 
'0.039uF'  | '25V'   | '10%'     | '0402V'    | 'EMPTY'  | 'A36096-063'(!) = 'YES;YES;YES;UNK;ok;VLD' | 'A36096-063'  | 'SMC0402A'  | '(SMX0402V,SMX0402AV,SMX0402BV)' | 'NA'       | '25V'         | '10%'    | 'DISCRETE' | 'CHIP0402'                                     | '0.024 IN' | 'CHIP0402'     | ''          | '1142' | 'http://speed.intel.com:8081/speed/module/pdm/item/pdm_item_detail_direct.asp?item_cde=A36096-063&item_rev=01&url_param=unused'  | 'Approved'    | 'NO'  | '7'   | 'SMO_BOARDS'      | '56' 
'0.039uF'  | '25V'   | '10%'     | '0402V'    | 'X7R'    | 'A36096-063'(!) = 'YES;YES;YES;UNK;ok;VLD' | 'A36096-063'  | 'SMC0402A'  | '(SMX0402V,SMX0402AV,SMX0402BV)' | '0.039uF'  | '25V'         | '10%'    | 'DISCRETE' | 'CHIP0402'                                     | '0.024 IN' | 'CHIP0402'     | ''          | '1142' | 'http://speed.intel.com:8081/speed/module/pdm/item/pdm_item_detail_direct.asp?item_cde=A36096-063&item_rev=01&url_param=unused'  | 'Approved'    | 'NO'  | '7'   | 'SMO_BOARDS'      | '56' 
'270pF'    | '50V'   | '10%'     | '0402V'    | 'EMPTY'  | 'A36096-065'(!) = 'YES;YES;YES;UNK;ok;VLD' | 'A36096-065'  | 'SMC0402A'  | '(SMX0402V,SMX0402AV,SMX0402BV)' | 'NA'       | '50V'         | '10%'    | 'DISCRETE' | 'CHIP0402'                                     | '0.024 IN' | 'CHIP0402'     | ''          | '1142' | 'http://speed.intel.com:8081/speed/module/pdm/item/pdm_item_detail_direct.asp?item_cde=A36096-065&item_rev=01&url_param=unused'  | 'Approved'    | 'NO'  | '7'   | 'SMO_BOARDS'      | '56' 
'270pF'    | '50V'   | '10%'     | '0402V'    | 'X7R'    | 'A36096-065'(!) = 'YES;YES;YES;UNK;ok;VLD' | 'A36096-065'  | 'SMC0402A'  | '(SMX0402V,SMX0402AV,SMX0402BV)' | '270pF'    | '50V'         | '10%'    | 'DISCRETE' | 'CHIP0402'                                     | '0.024 IN' | 'CHIP0402'     | ''          | '1142' | 'http://speed.intel.com:8081/speed/module/pdm/item/pdm_item_detail_direct.asp?item_cde=A36096-065&item_rev=01&url_param=unused'  | 'Approved'    | 'NO'  | '7'   | 'SMO_BOARDS'      | '56' 
'4700pF'   | '50V'   | '10%'     | '0402V'    | 'EMPTY'  | 'A36096-066'(!) = 'YES;YES;YES;UNK;ok;CIP' | 'A36096-066'  | 'SMC0402A'  | '(SMX0402V,SMX0402AV,SMX0402BV)' | 'NA'       | '50V'         | '10%'    | 'DISCRETE' | 'CHIP0402'                                     | '0.024 IN' | 'CHIP0402'     | ''          | '1142' | 'http://speed.intel.com:8081/speed/module/pdm/item/pdm_item_detail_direct.asp?item_cde=A36096-066&item_rev=01&url_param=unused'  | 'Approved'    | 'NO'  | '7'   | 'SMO_BOARDS'      | '56' 
'4700pF'   | '50V'   | '10%'     | '0402V'    | 'X7R'    | 'A36096-066'(!) = 'YES;YES;YES;UNK;ok;CIP' | 'A36096-066'  | 'SMC0402A'  | '(SMX0402V,SMX0402AV,SMX0402BV)' | '4700pF'   | '50V'         | '10%'    | 'DISCRETE' | 'CHIP0402'                                     | '0.024 IN' | 'CHIP0402'     | ''          | '1142' | 'http://speed.intel.com:8081/speed/module/pdm/item/pdm_item_detail_direct.asp?item_cde=A36096-066&item_rev=01&url_param=unused'  | 'Approved'    | 'NO'  | '7'   | 'SMO_BOARDS'      | '56' 
'0.022uF'  | '16V'   | '10%'     | '0402V'    | 'EMPTY'  | 'A36096-073'(!) = 'YES;YES;YES;UNK;ok;VLD' | 'A36096-073'  | 'SMC0402A'  | '(SMX0402V,SMX0402AV,SMX0402BV)' | 'NA'       | '16V'         | '10%'    | 'DISCRETE' | 'CHIP0402'                                     | '0.024 IN' | 'CHIP0402'     | ''          | '1142' | 'http://speed.intel.com:8081/speed/module/pdm/item/pdm_item_detail_direct.asp?item_cde=A36096-073&item_rev=01&url_param=unused'  | 'Approved'    | 'NO'  | '8'   | 'SMO_BOARDS'      | '56' 
'0.022uF'  | '16V'   | '10%'     | '0402V'    | 'X7R'    | 'A36096-073'(!) = 'YES;YES;YES;UNK;ok;VLD' | 'A36096-073'  | 'SMC0402A'  | '(SMX0402V,SMX0402AV,SMX0402BV)' | '0.022uF'  | '16V'         | '10%'    | 'DISCRETE' | 'CHIP0402'                                     | '0.024 IN' | 'CHIP0402'     | ''          | '1142' | 'http://speed.intel.com:8081/speed/module/pdm/item/pdm_item_detail_direct.asp?item_cde=A36096-073&item_rev=01&url_param=unused'  | 'Approved'    | 'NO'  | '8'   | 'SMO_BOARDS'      | '56' 
'2200pF'   | '50V'   | '10%'     | '0402V'    | 'EMPTY'  | 'A36096-075'(!) = 'YES;YES;YES;UNK;ok;CIP' | 'A36096-075'  | 'SMC0402A'  | '(SMX0402V,SMX0402AV,SMX0402BV)' | 'NA'       | '50V'         | '10%'    | 'DISCRETE' | 'CHIP0402'                                     | '0.024 IN' | 'CHIP0402'     | ''          | '1142' | 'http://speed.intel.com:8081/speed/module/pdm/item/pdm_item_detail_direct.asp?item_cde=A36096-075&item_rev=01&url_param=unused'  | 'Approved'    | 'NO'  | '7'   | 'SMO_BOARDS'      | '56' 
'2200pF'   | '50V'   | '10%'     | '0402V'    | 'X7R'    | 'A36096-075'(!) = 'YES;YES;YES;UNK;ok;CIP' | 'A36096-075'  | 'SMC0402A'  | '(SMX0402V,SMX0402AV,SMX0402BV)' | '2200pF'   | '50V'         | '10%'    | 'DISCRETE' | 'CHIP0402'                                     | '0.024 IN' | 'CHIP0402'     | ''          | '1142' | 'http://speed.intel.com:8081/speed/module/pdm/item/pdm_item_detail_direct.asp?item_cde=A36096-075&item_rev=01&url_param=unused'  | 'Approved'    | 'NO'  | '7'   | 'SMO_BOARDS'      | '56' 
'0.047uF'  | '25V'   | '10%'     | '0402V'    | 'EMPTY'  | 'A36096-090'(!) = 'YES;YES;YES;UNK;ok;VLD' | 'A36096-090'  | 'SMC0402A'  | '(SMX0402V,SMX0402AV,SMX0402BV)' | 'NA'       | '25V'         | '10%'    | 'DISCRETE' | 'CHIP0402'                                     | '0.020 IN' | 'CHIP0402'     | ''          | '1142' | 'http://speed.intel.com:8081/speed/module/pdm/item/pdm_item_detail_direct.asp?item_cde=A36096-090&item_rev=01&url_param=unused'  | 'Conditional' | 'YES' | '5'   | 'SMO_BOARDS'      | '14' 
'0.047uF'  | '25V'   | '10%'     | '0402V'    | 'X7R'    | 'A36096-090'(!) = 'YES;YES;YES;UNK;ok;VLD' | 'A36096-090'  | 'SMC0402A'  | '(SMX0402V,SMX0402AV,SMX0402BV)' | '0.047uF'  | '25V'         | '10%'    | 'DISCRETE' | 'CHIP0402'                                     | '0.020 IN' | 'CHIP0402'     | ''          | '1142' | 'http://speed.intel.com:8081/speed/module/pdm/item/pdm_item_detail_direct.asp?item_cde=A36096-090&item_rev=01&url_param=unused'  | 'Conditional' | 'YES' | '5'   | 'SMO_BOARDS'      | '14' 
'3300pF'   | '50V'   | '10%'     | '0402V'    | 'EMPTY'  | 'A36096-091'(!) = 'YES;YES;YES;UNK;ok;YTC' | 'A36096-091'  | 'SMC0402A'  | '(SMX0402V,SMX0402AV,SMX0402BV)' | 'NA'       | '50V'         | '10%'    | 'DISCRETE' | 'CHIP0402'                                     | '0.022 IN' | 'CHIP0402'     | ''          | '1142' | 'http://speed.intel.com:8081/speed/module/pdm/item/pdm_item_detail_direct.asp?item_cde=A36096-091&item_rev=01&url_param=unused'  | 'Approved'    | 'YES' | '8'   | 'SMO_BOARDS'      | '56' 
'3300pF'   | '50V'   | '10%'     | '0402V'    | 'X7R'    | 'A36096-091'(!) = 'YES;YES;YES;UNK;ok;YTC' | 'A36096-091'  | 'SMC0402A'  | '(SMX0402V,SMX0402AV,SMX0402BV)' | '3300pF'   | '50V'         | '10%'    | 'DISCRETE' | 'CHIP0402'                                     | '0.022 IN' | 'CHIP0402'     | ''          | '1142' | 'http://speed.intel.com:8081/speed/module/pdm/item/pdm_item_detail_direct.asp?item_cde=A36096-091&item_rev=01&url_param=unused'  | 'Approved'    | 'YES' | '8'   | 'SMO_BOARDS'      | '56' 
'0.220uF'  | '16V'   | '10%'     | '0402V'    | 'EMPTY'  | 'A36096-104'(!) = 'YES;YES;YES;UNK;ok;VLD' | 'A36096-104'  | 'SMC0402A'  | '(SMX0402V,SMX0402AV,SMX0402BV)' | 'NA'       | '16V'         | '10%'    | 'DISCRETE' | 'CHIP0402'                                     | '0.022 IN' | 'CHIP0402'     | ''          | '1142' | 'http://speed.intel.com:8081/speed/module/pdm/item/pdm_item_detail_direct.asp?item_cde=A36096-104&item_rev=01&url_param=unused'  | 'Conditional' | 'YES' | '3'   | 'SMO_BOARDS'      | '56' 
'0.220uF'  | '16V'   | '10%'     | '0402V'    | 'X7R'    | 'A36096-104'(!) = 'YES;YES;YES;UNK;ok;VLD' | 'A36096-104'  | 'SMC0402A'  | '(SMX0402V,SMX0402AV,SMX0402BV)' | '0.220uF'  | '16V'         | '10%'    | 'DISCRETE' | 'CHIP0402'                                     | '0.022 IN' | 'CHIP0402'     | ''          | '1142' | 'http://speed.intel.com:8081/speed/module/pdm/item/pdm_item_detail_direct.asp?item_cde=A36096-104&item_rev=01&url_param=unused'  | 'Conditional' | 'YES' | '3'   | 'SMO_BOARDS'      | '56' 
'0.027uF'  | '16V'   | '10%'     | '0402V'    | 'EMPTY'  | 'A36096-129'(!) = 'UNK;UNK;UNK;UNK;ok;CIP' | 'A36096-129'  | 'SMC0402A'  | '(SMX0402V,SMX0402AV,SMX0402BV)' | 'NA'       | '16V'         | '10%'    | 'DISCRETE' | 'CHIP0402'                                     | '0.022 IN' | 'CHIP0402'     | ''          | '1142' | 'http://speed.intel.com:8081/speed/module/pdm/item/pdm_item_detail_direct.asp?item_cde=A36096-129&item_rev=01&url_param=unused'  | 'Design'      | 'YES' | '2'   | 'SMO_BOARDS'      | '???'
'0.027uF'  | '16V'   | '10%'     | '0402V'    | 'X7R'    | 'A36096-129'(!) = 'UNK;UNK;UNK;UNK;ok;CIP' | 'A36096-129'  | 'SMC0402A'  | '(SMX0402V,SMX0402AV,SMX0402BV)' | '0.027uF'  | '16V'         | '10%'    | 'DISCRETE' | 'CHIP0402'                                     | '0.022 IN' | 'CHIP0402'     | ''          | '1142' | 'http://speed.intel.com:8081/speed/module/pdm/item/pdm_item_detail_direct.asp?item_cde=A36096-129&item_rev=01&url_param=unused'  | 'Design'      | 'YES' | '2'   | 'SMO_BOARDS'      | '???'
'0.22uF'   | '16V'   | '10%'     | '0402V'    | 'EMPTY'  | 'A36096-155'(!) = ''                       | 'A36096-155'  | 'SMC0402A'  | '(SMX0402V,SMX0402AV,SMX0402BV)' | 'NA'       | '16V'         | '10%'    | 'DISCRETE' | 'CAPC,X7R,0402,0.22UF,16.00V, 10%'             | '0.022 IN' | 'CHIP0402'     | ''          | '1142' | 'http://speed.intel.com:8081/speed/module/pdm/item/pdm_item_detail_direct.asp?item_cde=A36096-155&item_rev=01&url_param=unused'  | ''            | ''    | ''    | ''                | ''   
'0.22uF'   | '16V'   | '10%'     | '0402V'    | 'X7R'    | 'A36096-155'(!) = ''                       | 'A36096-155'  | 'SMC0402A'  | '(SMX0402V,SMX0402AV,SMX0402BV)' | '0.22uF'   | '16V'         | '10%'    | 'DISCRETE' | 'CAPC,X7R,0402,0.22UF,16.00V, 10%'             | '0.022 IN' | 'CHIP0402'     | ''          | '1142' | 'http://speed.intel.com:8081/speed/module/pdm/item/pdm_item_detail_direct.asp?item_cde=A36096-155&item_rev=01&url_param=unused'  | ''            | ''    | ''    | ''                | ''   
'1.0uF'    | '6.3V'  | '10%'     | '0402V'    | 'EMPTY'  | 'D97712-004'(!) = 'YES;YES;YES;UNK;ok;VLD' | 'D97712-004'  | 'SMC0402A'  | '(SMX0402V,SMX0402AV,SMX0402BV)' | 'NA'       | '6.3V'        | '10%'    | 'DISCRETE' | 'CHIP0402'                                     | '0.022 IN' | 'CHIP0402'     | ''          | '1142' | 'http://speed.intel.com:8081/speed/module/pdm/item/pdm_item_detail_direct.asp?item_cde=D97712-004&item_rev=01&url_param=unused'  | 'Conditional' | 'NO'  | '4'   | 'SMO_BOARDS'      | '???'
'1.0uF'    | '6.3V'  | '10%'     | '0402V'    | 'X6S'    | 'D97712-004'(!) = 'YES;YES;YES;UNK;ok;VLD' | 'D97712-004'  | 'SMC0402A'  | '(SMX0402V,SMX0402AV,SMX0402BV)' | '1.0uF'    | '6.3V'        | '10%'    | 'DISCRETE' | 'CHIP0402'                                     | '0.022 IN' | 'CHIP0402'     | ''          | '1142' | 'http://speed.intel.com:8081/speed/module/pdm/item/pdm_item_detail_direct.asp?item_cde=D97712-004&item_rev=01&url_param=unused'  | 'Conditional' | 'NO'  | '4'   | 'SMO_BOARDS'      | '???'
'1.0uF'    | '16V'   | '10%'     | '0402V'    | 'EMPTY'  | 'D97712-011'(!) = ''                       | 'D97712-011'  | 'SMC0402A'  | '(SMX0402V,SMX0402AV,SMX0402BV)' | 'NA'       | '16V'         | '10%'    | 'DISCRETE' | 'CAPC,X6S,0402,1.00UF,16.00V, 10%'             | '0.024 IN' | 'CHIP0402'     | ''          | '1142' | 'http://speed.intel.com:8081/speed/module/pdm/item/pdm_item_detail_direct.asp?item_cde=D97712-011&item_rev=01&url_param=unused'  | ''            | ''    | ''    | ''                | ''   
'1.0uF'    | '16V'   | '10%'     | '0402V'    | 'X6S'    | 'D97712-011'(!) = ''                       | 'D97712-011'  | 'SMC0402A'  | '(SMX0402V,SMX0402AV,SMX0402BV)' | '1.0uF'    | '16V'         | '10%'    | 'DISCRETE' | 'CAPC,X6S,0402,1.00UF,16.00V, 10%'             | '0.024 IN' | 'CHIP0402'     | ''          | '1142' | 'http://speed.intel.com:8081/speed/module/pdm/item/pdm_item_detail_direct.asp?item_cde=D97712-011&item_rev=01&url_param=unused'  | ''            | ''    | ''    | ''                | ''   
'1.0uF'    | '16V'   | '10%'     | '0402V'    | 'EMPTY'  | 'G71842-007'(!) = 'UNK;UNK;UNK;UNK;ok;CIP' | 'G71842-007'  | 'SMC0402A'  | '(SMX0402V,SMX0402AV,SMX0402BV)' | 'NA'       | '16V'         | '10%'    | 'DISCRETE' | 'CAPC,X7S,0402,1.00UF,16.00V, 10%'             | '0.024 IN' | 'CHIP0402'     | ''          | '1142' | 'http://speed.intel.com:8081/speed/module/pdm/item/pdm_item_detail_direct.asp?item_cde=G71842-007&item_rev=01&url_param=unused'  | 'Design'      | 'NO'  | '1'   | 'SMO_BOARDS'      | '???'
'1.0uF'    | '16V'   | '10%'     | '0402V'    | 'X7S'    | 'G71842-007'(!) = 'UNK;UNK;UNK;UNK;ok;CIP' | 'G71842-007'  | 'SMC0402A'  | '(SMX0402V,SMX0402AV,SMX0402BV)' | '1.0uF'    | '16V'         | '10%'    | 'DISCRETE' | 'CAPC,X7S,0402,1.00UF,16.00V, 10%'             | '0.024 IN' | 'CHIP0402'     | ''          | '1142' | 'http://speed.intel.com:8081/speed/module/pdm/item/pdm_item_detail_direct.asp?item_cde=G71842-007&item_rev=01&url_param=unused'  | 'Design'      | 'NO'  | '1'   | 'SMO_BOARDS'      | '???'
'0.47uF'   | '16V'   | '10%'     | '0603V'    | 'EMPTY'  | '202297-006'(!) = 'YES;YES;YES;UNK;ok;VLD' | '202297-006'  | 'SMC0603A'  | '(SMX0603V)'                     | 'NA'       | '16V'         | '10%'    | 'DISCRETE' | 'CAPC,X7R,0603,0.470UF,16.000V, 10%'           | '0.035 IN' | 'CHIP0603'     | ''          | '443'  | 'http://speed.intel.com:8081/speed/module/pdm/item/pdm_item_detail_direct.asp?item_cde=202297-006&item_rev=01&url_param=unused'  | 'Conditional' | 'NO'  | '7'   | 'SMO_BOARDS'      | '56' 
'0.47uF'   | '16V'   | '10%'     | '0603V'    | 'X7R'    | '202297-006'(!) = 'YES;YES;YES;UNK;ok;VLD' | '202297-006'  | 'SMC0603A'  | '(SMX0603V)'                     | '0.47uF'   | '16V'         | '10%'    | 'DISCRETE' | 'CAPC,X7R,0603,0.470UF,16.000V, 10%'           | '0.035 IN' | 'CHIP0603'     | ''          | '443'  | 'http://speed.intel.com:8081/speed/module/pdm/item/pdm_item_detail_direct.asp?item_cde=202297-006&item_rev=01&url_param=unused'  | 'Conditional' | 'NO'  | '7'   | 'SMO_BOARDS'      | '56' 
'0.1uF'    | '25V'   | '10%'     | '0603V'    | 'EMPTY'  | '602433-020'(!) = 'YES;YES;YES;UNK;ok;VLD' | '602433-020'  | 'SMC0603A'  | '(SMX0603V)'                     | 'NA'       | '25V'         | '10%'    | 'DISCRETE' | 'CHIP0603'                                     | '0.035 IN' | 'CHIP0603'     | ''          | '443'  | 'http://speed.intel.com:8081/speed/module/pdm/item/pdm_item_detail_direct.asp?item_cde=602433-020&item_rev=01&url_param=unused'  | 'Conditional' | 'YES' | '9'   | 'SMO_BOARDS'      | '56' 
'0.1uF'    | '25V'   | '10%'     | '0603V'    | 'X7R'    | '602433-020'(!) = 'YES;YES;YES;UNK;ok;VLD' | '602433-020'  | 'SMC0603A'  | '(SMX0603V)'                     | '0.1uF'    | '25V'         | '10%'    | 'DISCRETE' | 'CHIP0603'                                     | '0.035 IN' | 'CHIP0603'     | ''          | '443'  | 'http://speed.intel.com:8081/speed/module/pdm/item/pdm_item_detail_direct.asp?item_cde=602433-020&item_rev=01&url_param=unused'  | 'Conditional' | 'YES' | '9'   | 'SMO_BOARDS'      | '56' 
'47uF'     | '4V'    | '20%'     | '0603V'    | 'EMPTY'  | '602433-106'(!) = ''                       | '602433-106'  | 'SMC0603CV' | ''                               | 'NA'       | '4V'          | '20%'    | 'DISCRETE' | 'CAPC,X5R,0603,47.00UF,4.00V, 20%'             | '0.039 IN' | 'CHIP0603'     | ''          | '3802' | 'http://speed.intel.com:8081/speed/module/pdm/item/pdm_item_detail_direct.asp?item_cde=602433-106&item_rev=01&url_param=unused'  | ''            | ''    | ''    | ''                | ''   
'47uF'     | '4V'    | '20%'     | '0603V'    | 'X5R'    | '602433-106'(!) = ''                       | '602433-106'  | 'SMC0603CV' | ''                               | '47uF'     | '4V'          | '20%'    | 'DISCRETE' | 'CAPC,X5R,0603,47.00UF,4.00V, 20%'             | '0.039 IN' | 'CHIP0603'     | ''          | '3802' | 'http://speed.intel.com:8081/speed/module/pdm/item/pdm_item_detail_direct.asp?item_cde=602433-106&item_rev=01&url_param=unused'  | ''            | ''    | ''    | ''                | ''   
'0.033uF'  | '50V'   | '10%'     | '0603V'    | 'EMPTY'  | '603269-064'(!) = 'YES;YES;UNK;UNK;ok;VLD' | '603269-064'  | 'SMC0603A'  | '(SMX0603V)'                     | 'NA'       | '50V'         | '10%'    | 'DISCRETE' | 'CHIP0603'                                     | '0.035 IN' | 'CHIP0603'     | ''          | '443'  | 'http://speed.intel.com:8081/speed/module/pdm/item/pdm_item_detail_direct.asp?item_cde=603269-064&item_rev=01&url_param=unused'  | 'Approved'    | 'YES' | '8'   | 'SMO_BOARDS'      | '56' 
'0.033uF'  | '50V'   | '10%'     | '0603V'    | 'X7R'    | '603269-064'(!) = 'YES;YES;UNK;UNK;ok;VLD' | '603269-064'  | 'SMC0603A'  | '(SMX0603V)'                     | '0.033uF'  | '50V'         | '10%'    | 'DISCRETE' | 'CHIP0603'                                     | '0.035 IN' | 'CHIP0603'     | ''          | '443'  | 'http://speed.intel.com:8081/speed/module/pdm/item/pdm_item_detail_direct.asp?item_cde=603269-064&item_rev=01&url_param=unused'  | 'Approved'    | 'YES' | '8'   | 'SMO_BOARDS'      | '56' 
'10uF'     | '4V'    | '20%'     | '0603V'    | 'EMPTY'  | 'E15431-001'(!) = 'YES;YES;YES;UNK;ok;VLD' | 'E15431-001'  | 'SMC0603A'  | '(SMX0603V)'                     | 'NA'       | '4V'          | '20%'    | 'DISCRETE' | 'CHIP0603'                                     | '0.037 IN' | 'CHIP0603'     | ''          | '443'  | 'http://speed.intel.com:8081/speed/module/pdm/item/pdm_item_detail_direct.asp?item_cde=E15431-001&item_rev=01&url_param=unused'  | 'Conditional' | 'NO'  | '3'   | 'SMO_BOARDS'      | '???'
'10uF'     | '4V'    | '20%'     | '0603V'    | 'X6S'    | 'E15431-001'(!) = 'YES;YES;YES;UNK;ok;VLD' | 'E15431-001'  | 'SMC0603A'  | '(SMX0603V)'                     | '10uF'     | '4V'          | '20%'    | 'DISCRETE' | 'CHIP0603'                                     | '0.027 IN' | 'CHIP0603'     | ''          | '443'  | 'http://speed.intel.com:8081/speed/module/pdm/item/pdm_item_detail_direct.asp?item_cde=E15431-001&item_rev=01&url_param=unused'  | 'Conditional' | 'NO'  | '3'   | 'SMO_BOARDS'      | '???'
'10uF'     | '6.3V'  | '20%'     | '0603V'    | 'EMPTY'  | 'E15431-002'(!) = 'YES;YES;YES;UNK;ok;VLD' | 'E15431-002'  | 'SMC0603A'  | '(SMX0603V)'                     | 'NA'       | '6.3V'        | '20%'    | 'DISCRETE' | 'CHIP0603'                                     | '0.039 IN' | 'CHIP0603'     | ''          | '443'  | 'http://speed.intel.com:8081/speed/module/pdm/item/pdm_item_detail_direct.asp?item_cde=E15431-002&item_rev=01&url_param=unused'  | 'Conditional' | 'NO'  | '2'   | 'SMO_BOARDS'      | '56' 
'10uF'     | '6.3V'  | '20%'     | '0603V'    | 'X6S'    | 'E15431-002'(!) = 'YES;YES;YES;UNK;ok;VLD' | 'E15431-002'  | 'SMC0603A'  | '(SMX0603V)'                     | '10uF'     | '6.3V'        | '20%'    | 'DISCRETE' | 'CHIP0603'                                     | '0.039 IN' | 'CHIP0603'     | ''          | '443'  | 'http://speed.intel.com:8081/speed/module/pdm/item/pdm_item_detail_direct.asp?item_cde=E15431-002&item_rev=01&url_param=unused'  | 'Conditional' | 'NO'  | '2'   | 'SMO_BOARDS'      | '56' 
'4.7uF'    | '6.3V'  | '10%'     | '0603V'    | 'EMPTY'  | 'E15431-003'(!) = 'YES;YES;YES;UNK;ok;VLD' | 'E15431-003'  | 'SMC0603A'  | '(SMX0603V)'                     | 'NA'       | '6.3V'        | '10%'    | 'DISCRETE' | 'CHIP0603'                                     | '0.035 IN' | 'CHIP0603'     | ''          | '443'  | 'http://speed.intel.com:8081/speed/module/pdm/item/pdm_item_detail_direct.asp?item_cde=E15431-003&item_rev=01&url_param=unused'  | 'Conditional' | 'NO'  | '5'   | 'SMO_BOARDS'      | '???'
'4.7uF'    | '6.3V'  | '10%'     | '0603V'    | 'X6S'    | 'E15431-003'(!) = 'YES;YES;YES;UNK;ok;VLD' | 'E15431-003'  | 'SMC0603A'  | '(SMX0603V)'                     | '4.7uF'    | '6.3V'        | '10%'    | 'DISCRETE' | 'CHIP0603'                                     | '0.035 IN' | 'CHIP0603'     | ''          | '443'  | 'http://speed.intel.com:8081/speed/module/pdm/item/pdm_item_detail_direct.asp?item_cde=E15431-003&item_rev=01&url_param=unused'  | 'Conditional' | 'NO'  | '5'   | 'SMO_BOARDS'      | '???'
'22.0uF'   | '4V'    | '20%'     | '0603V'    | 'EMPTY'  | 'E15431-004'(!) = 'YES;YES;YES;UNK;ok;VLD' | 'E15431-004'  | 'SMC0603A'  | '(SMX0603V)'                     | 'NA'       | '4V'          | '20%'    | 'DISCRETE' | 'CAPC,X6S,0603,22.00UF,4.00V, 20%'             | '0.035 IN' | 'CHIP0603'     | ''          | '443'  | 'http://speed.intel.com:8081/speed/module/pdm/item/pdm_item_detail_direct.asp?item_cde=E15431-004&item_rev=01&url_param=unused'  | 'Design'      | 'NO'  | '2'   | 'SMO_BOARDS'      | '???'
'22.0uF'   | '4V'    | '20%'     | '0603V'    | 'X6S'    | 'E15431-004'(!) = 'YES;YES;YES;UNK;ok;VLD' | 'E15431-004'  | 'SMC0603A'  | '(SMX0603V)'                     | '22.0uF'   | '4V'          | '20%'    | 'DISCRETE' | 'CAPC,X6S,0603,22.00UF,4.00V, 20%'             | '0.035 IN' | 'CHIP0603'     | ''          | '443'  | 'http://speed.intel.com:8081/speed/module/pdm/item/pdm_item_detail_direct.asp?item_cde=E15431-004&item_rev=01&url_param=unused'  | 'Design'      | 'NO'  | '2'   | 'SMO_BOARDS'      | '???'
END_PART
END.
